# S9S_MB_2U (Grand Teton) — schematic netlist excerpt (pin names and nets, part order shuffled) for the footprints in the layout excerpt that follows; sources: Cadence DE-HDL packaged netlist, KiCad conversion of 03242023_DA0F0TMBIJ0_F0T_Motherboard_J_brd_V01_OCP.brd

J11  SCONN288_ADR50017P130CC  SCONN288_ADR50017-P130CC IO  pkg DDR288S_1-1VXB  page 92
  VIN_BULK0  = P12V_S3_AUX_CPU0_NVDIMM
  RFU0  = TP_CHF_CPU0_DIMM1_FRU_0
  VIN_MGMT  = P3V3_AUX
  HSCL  = I3C_SPD_DDREFGH_CPU0_LVC1_SCL_2
  HSDA  = I3C_SPD_DDREFGH_CPU0_LVC1_SDA
  VSS0  = GND
  DQ0_A  = M_F_CPU0_SA_DQ<0>
  VSS1  = GND
  DQ1_A  = M_F_CPU0_SA_DQ<1>
  VSS2  = GND
  DQS0_A_T  = M_F_CPU0_SA_DQS_DP<0>
  DQS0_A_C  = M_F_CPU0_SA_DQS_DN<0>
  VSS3  = GND
  DQ4_A  = M_F_CPU0_SA_DQ<4>
  VSS4  = GND
  DQ5_A  = M_F_CPU0_SA_DQ<5>
  VSS5  = GND
  DQ8_A  = M_F_CPU0_SA_DQ<8>
  VSS6  = GND
  DQ9_A  = M_F_CPU0_SA_DQ<9>
  VSS7  = GND
  DQS1_A_T  = M_F_CPU0_SA_DQS_DP<1>
  DQS1_A_C  = M_F_CPU0_SA_DQS_DN<1>
  VSS8  = GND
  DQ12_A  = M_F_CPU0_SA_DQ<12>
  VSS9  = GND
  DQ13_A  = M_F_CPU0_SA_DQ<13>
  VSS10  = GND
  DQ16_A  = M_F_CPU0_SA_DQ<16>
  VSS11  = GND
  DQ17_A  = M_F_CPU0_SA_DQ<17>
  VSS12  = GND
  DQS2_A_T  = M_F_CPU0_SA_DQS_DP<2>
  DQS2_A_C  = M_F_CPU0_SA_DQS_DN<2>
  VSS13  = GND
  DQ20_A  = M_F_CPU0_SA_DQ<20>
  VSS14  = GND
  DQ21_A  = M_F_CPU0_SA_DQ<21>
  VSS15  = GND
  DQ24_A  = M_F_CPU0_SA_DQ<24>
  VSS16  = GND
  DQ25_A  = M_F_CPU0_SA_DQ<25>
  VSS17  = GND
  DQS3_A_T  = M_F_CPU0_SA_DQS_DP<3>
  DQS3_A_C  = M_F_CPU0_SA_DQS_DN<3>
  VSS18  = GND
  DQ28_A  = M_F_CPU0_SA_DQ<28>
  VSS19  = GND
  DQ29_A  = M_F_CPU0_SA_DQ<29>
  VSS20  = GND
  CB0_A  = M_F_CPU0_SA_CB<0>
  VSS21  = GND
  CB1_A  = M_F_CPU0_SA_CB<1>
  VSS22  = GND
  DQS4_A_T  = M_F_CPU0_SA_DQS_DP<4>
  DQS4_A_C  = M_F_CPU0_SA_DQS_DN<4>
  VSS23  = GND
  CB4_A  = M_F_CPU0_SA_CB<4>
  VSS24  = GND
  CB5_A  = M_F_CPU0_SA_CB<5>
  VSS25  = GND
  ALERT_N  = M_F_CPU0_ALERT_N
  VSS26  = GND
  CS0_A_N  = M_F_CPU0_SA_CS_N<0>
  VSS27  = GND
  CA0_A  = M_F_CPU0_SA_CA<0>
  VSS28  = GND
  CA2_A  = M_F_CPU0_SA_CA<2>
  VSS29  = GND
  CA4_A  = M_F_CPU0_SA_CA<4>
  VSS30  = GND
  CA6_A  = M_F_CPU0_SA_CA<6>
  VSS31  = GND
  PAR_A  = M_F_CPU0_SA_PAR
  VSS32  = GND
  CA0_B  = M_F_CPU0_SB_CA<0>
  VSS33  = GND
  CA2_B  = M_F_CPU0_SB_CA<2>
  VSS34  = GND
  CA4_B  = M_F_CPU0_SB_CA<4>
  VSS35  = GND
  CA6_B  = M_F_CPU0_SB_CA<6>
  VSS36  = GND
  CS0_B_N  = M_F_CPU0_SB_CS_N<0>
  VSS37  = GND
  \lbd||rsp_a_n\  = M_F_CPU0_SA_RSP<0>
  \lbs||rsp_b_n\  = M_F_CPU0_SB_RSP<0>
  VSS38  = GND
  CB4_B  = M_F_CPU0_SB_CB<4>
  VSS39  = GND
  CB5_B  = M_F_CPU0_SB_CB<5>
  VSS40  = GND
  \dqs9_b_t||tdqs9_b_t||dbi4_b_n\  = M_F_CPU0_SB_DQS_DP<9>
  \dqs9_b_c||tdqs9_b_c\  = M_F_CPU0_SB_DQS_DN<9>
  VSS41  = GND
  CB0_B  = M_F_CPU0_SB_CB<0>
  VSS42  = GND
  CB1_B  = M_F_CPU0_SB_CB<1>
  VSS43  = GND
  DQ0_B  = M_F_CPU0_SB_DQ<0>
  VSS44  = GND
  DQ1_B  = M_F_CPU0_SB_DQ<1>
  VSS45  = GND
  DQS0_B_T  = M_F_CPU0_SB_DQS_DP<0>
  DQS0_B_C  = M_F_CPU0_SB_DQS_DN<0>
  VSS46  = GND
  DQ4_B  = M_F_CPU0_SB_DQ<4>
  VSS47  = GND
  DQ5_B  = M_F_CPU0_SB_DQ<5>
  VSS48  = GND
  DQ8_B  = M_F_CPU0_SB_DQ<8>
  VSS49  = GND
  DQ9_B  = M_F_CPU0_SB_DQ<9>
  VSS50  = GND
  DQS1_B_T  = M_F_CPU0_SB_DQS_DP<1>
  DQS1_B_C  = M_F_CPU0_SB_DQS_DN<1>
  VSS51  = GND
  DQ12_B  = M_F_CPU0_SB_DQ<12>
  VSS52  = GND
  DQ13_B  = M_F_CPU0_SB_DQ<13>
  VSS53  = GND
  DQ16_B  = M_F_CPU0_SB_DQ<16>
  VSS54  = GND
  DQ17_B  = M_F_CPU0_SB_DQ<17>
  VSS55  = GND
  DQS2_B_T  = M_F_CPU0_SB_DQS_DP<2>
  DQS2_B_C  = M_F_CPU0_SB_DQS_DN<2>
  VSS56  = GND
  DQ20_B  = M_F_CPU0_SB_DQ<20>
  VSS57  = GND
  DQ21_B  = M_F_CPU0_SB_DQ<21>
  VSS58  = GND
  DQ24_B  = M_F_CPU0_SB_DQ<24>
  VSS59  = GND
  DQ25_B  = M_F_CPU0_SB_DQ<25>
  VSS60  = GND
  DQS3_B_T  = M_F_CPU0_SB_DQS_DP<3>
  DQS3_B_C  = M_F_CPU0_SB_DQS_DN<3>
  VSS61  = GND
  DQ28_B  = M_F_CPU0_SB_DQ<28>
  VSS62  = GND
  DQ29_B  = M_F_CPU0_SB_DQ<29>
  VSS63  = GND
  RFU1  = TP_CHF_CPU0_DIMM1_FRU_1
  VIN_BULK1  = P12V_S3_AUX_CPU0_NVDIMM
  VIN_BULK2  = P12V_S3_AUX_CPU0_NVDIMM
  \pwr_good||fail_n\  = PWRGD_CHF_CPU0_DIMM1
  HSA  = PD_CHF_CPU0_DIMM1_SAA
  RFU2  = TP_CHF_CPU0_DIMM1_FRU_2
  RFU3  = TP_CHF_CPU0_DIMM1_FRU_3
  VSS64  = GND
  DQ2_A  = M_F_CPU0_SA_DQ<2>
  VSS65  = GND
  DQ3_A  = M_F_CPU0_SA_DQ<3>
  VSS66  = GND
  \dqs5_a_c||tdqs5_a_c||dqs5_a_t||tdqs5_a_t\  = M_F_CPU0_SA_DQS_DN<5>
  \dqs5_a_t||tdqs5_a_t\  = M_F_CPU0_SA_DQS_DP<5>
  VSS67  = GND
  DQ6_A  = M_F_CPU0_SA_DQ<6>
  VSS68  = GND
  DQ7_A  = M_F_CPU0_SA_DQ<7>
  VSS69  = GND
  DQ10_A  = M_F_CPU0_SA_DQ<10>
  VSS70  = GND
  DQ11_A  = M_F_CPU0_SA_DQ<11>
  VSS71  = GND
  \dqs6_a_c||tdqs6_a_c||dqs6_a_t||tdqs6_a_t\  = M_F_CPU0_SA_DQS_DN<6>
  \dqs6_a_t||tdqs6_a_t\  = M_F_CPU0_SA_DQS_DP<6>
  VSS72  = GND
  DQ14_A  = M_F_CPU0_SA_DQ<14>
  VSS73  = GND
  DQ15_A  = M_F_CPU0_SA_DQ<15>
  VSS74  = GND
  DQ18_A  = M_F_CPU0_SA_DQ<18>
  VSS75  = GND
  DQ19_A  = M_F_CPU0_SA_DQ<19>
  VSS76  = GND
  \dqs7_a_c||tdqs7_a_c\  = M_F_CPU0_SA_DQS_DN<7>
  \dqs7_a_t||tdqs7_a_t\  = M_F_CPU0_SA_DQS_DP<7>
  VSS77  = GND
  DQ22_A  = M_F_CPU0_SA_DQ<22>
  VSS78  = GND
  DQ23_A  = M_F_CPU0_SA_DQ<23>
  VSS79  = GND
  DQ26_A  = M_F_CPU0_SA_DQ<26>
  VSS80  = GND
  DQ27_A  = M_F_CPU0_SA_DQ<27>
  VSS81  = GND
  \dqs8_a_c||tdqs8_a_c\  = M_F_CPU0_SA_DQS_DN<8>
  \dqs8_a_t||tdqs8_a_t\  = M_F_CPU0_SA_DQS_DP<8>
  VSS82  = GND
  DQ30_A  = M_F_CPU0_SA_DQ<30>
  VSS83  = GND
  DQ31_A  = M_F_CPU0_SA_DQ<31>
  VSS84  = GND
  CB2_A  = M_F_CPU0_SA_CB<2>
  VSS85  = GND
  CB3_A  = M_F_CPU0_SA_CB<3>
  VSS86  = GND
  \dqs9_a_c||tdqs9_a_c\  = M_F_CPU0_SA_DQS_DN<9>
  \dqs9_a_t||tdqs9_a_t\  = M_F_CPU0_SA_DQS_DP<9>
  VSS87  = GND
  CB6_A  = M_F_CPU0_SA_CB<6>
  VSS88  = GND
  CB7_A  = M_F_CPU0_SA_CB<7>
  VSS89  = GND
  RESET_N  = RST_M_EF_CPU0_FPGA_N
  VSS90  = GND
  CS1_A_N  = M_F_CPU0_SA_CS_N<1>
  VSS91  = GND
  CA1_A  = M_F_CPU0_SA_CA<1>
  VSS92  = GND
  CA3_A  = M_F_CPU0_SA_CA<3>
  VSS93  = GND
  CA5_A  = M_F_CPU0_SA_CA<5>
  VSS94  = GND
  CK_T  = M_F_CPU0_CLK_DP<0>
  CK_C  = M_F_CPU0_CLK_DN<0>
  VSS95  = GND
  RFU4  = TP_CHF_CPU0_DIMM1_FRU_4
  CA1_B  = M_F_CPU0_SB_CA<1>
  VSS96  = GND
  CA3_B  = M_F_CPU0_SB_CA<3>
  VSS97  = GND
  CA5_B  = M_F_CPU0_SB_CA<5>
  VSS98  = GND
  PAR_B  = M_F_CPU0_SB_PAR
  VSS99  = GND
  CS1_B_N  = M_F_CPU0_SB_CS_N<1>
  VSS100  = GND
  RFU5  = TP_CHF_CPU0_DIMM1_FRU_5
  RFU6  = TP_CHF_CPU0_DIMM1_FRU_6
  VSS101  = GND
  CB6_B  = M_F_CPU0_SB_CB<6>
  VSS102  = GND
  CB7_B  = M_F_CPU0_SB_CB<7>
  VSS103  = GND
  DQS4_B_C  = M_F_CPU0_SB_DQS_DN<4>
  DQS4_B_T  = M_F_CPU0_SB_DQS_DP<4>
  VSS104  = GND
  CB2_B  = M_F_CPU0_SB_CB<2>
  VSS105  = GND
  CB3_B  = M_F_CPU0_SB_CB<3>
  VSS106  = GND
  DQ2_B  = M_F_CPU0_SB_DQ<2>
  VSS107  = GND
  DQ3_B  = M_F_CPU0_SB_DQ<3>
  VSS108  = GND
  \dqs5_b_c||tdqs5_b_c\  = M_F_CPU0_SB_DQS_DN<5>
  \dqs5_b_t||tdqs5_b_t\  = M_F_CPU0_SB_DQS_DP<5>
  VSS109  = GND
  DQ6_B  = M_F_CPU0_SB_DQ<6>
  VSS110  = GND
  DQ7_B  = M_F_CPU0_SB_DQ<7>
  VSS111  = GND
  DQ10_B  = M_F_CPU0_SB_DQ<10>
  VSS112  = GND
  DQ11_B  = M_F_CPU0_SB_DQ<11>
  VSS113  = GND
  \dqs6_b_c||tdqs6_b_c\  = M_F_CPU0_SB_DQS_DN<6>
  \dqs6_b_t||tdqs6_b_t\  = M_F_CPU0_SB_DQS_DP<6>
  VSS114  = GND
  DQ14_B  = M_F_CPU0_SB_DQ<14>
  VSS115  = GND
  DQ15_B  = M_F_CPU0_SB_DQ<15>
  VSS116  = GND
  DQ18_B  = M_F_CPU0_SB_DQ<18>
  VSS117  = GND
  DQ19_B  = M_F_CPU0_SB_DQ<19>
  VSS118  = GND
  \dqs7_b_c||tdqs7_b_c\  = M_F_CPU0_SB_DQS_DN<7>
  \dqs7_b_t||tdqs7_b_t\  = M_F_CPU0_SB_DQS_DP<7>
  VSS119  = GND
  DQ22_B  = M_F_CPU0_SB_DQ<22>
  VSS120  = GND
  DQ23_B  = M_F_CPU0_SB_DQ<23>
  VSS121  = GND
  DQ26_B  = M_F_CPU0_SB_DQ<26>
  VSS122  = GND
  DQ27_B  = M_F_CPU0_SB_DQ<27>
  VSS123  = GND
  \dqs8_b_c||tdqs8_b_c\  = M_F_CPU0_SB_DQS_DN<8>
  \dqs8_b_t||tdqs8_b_t\  = M_F_CPU0_SB_DQS_DP<8>
  VSS124  = GND
  DQ30_B  = M_F_CPU0_SB_DQ<30>
  VSS125  = GND
  DQ31_B  = M_F_CPU0_SB_DQ<31>
  VSS126  = GND
  G1  = GND
  G2  = GND
  G3  = GND

(kicad_pcb
	(version 20260206)
	(generator "pcbnew")
	(generator_version "10.0")
	(general
		(thickness 1.6)
		(legacy_teardrops no)
	)
	(paper "A4")
	(title_block
		(title "03242023_DA0F0TMBIJ0_F0T_Motherboard_J_brd_V01_OCP.brd")
		(comment 1 "Grand Teton / footprint 1952 of 6105 (J11), pads 229-274 of 291")
	)
	(layers
		(0 "F.Cu" signal "TOP")
		(4 "In1.Cu" signal "GND")
		(6 "In2.Cu" signal "IN1")
		(8 "In3.Cu" signal "GND1")
		(10 "In4.Cu" signal "IN2")
		(12 "In5.Cu" signal "GND2")
		(14 "In6.Cu" signal "IN3")
		(16 "In7.Cu" signal "GND3")
		(18 "In8.Cu" signal "VCC")
		(20 "In9.Cu" signal "VCC1")
		(22 "In10.Cu" signal "GND4")
		(24 "In11.Cu" signal "IN4")
		(26 "In12.Cu" signal "GND5")
		(28 "In13.Cu" signal "IN5")
		(30 "In14.Cu" signal "GND6")
		(32 "In15.Cu" signal "IN6")
		(34 "In16.Cu" signal "GND7")
		(2 "B.Cu" signal "BOTTOM")
		(9 "F.Adhes" user "F.Adhesive")
		(11 "B.Adhes" user "B.Adhesive")
		(13 "F.Paste" user "Package Geometry/Pastemask Top")
		(15 "B.Paste" user "Package Geometry/Pastemask Bottom")
		(5 "F.SilkS" user "Ref Des/Silkscreen Top")
		(7 "B.SilkS" user "Ref Des/Silkscreen Bottom")
		(1 "F.Mask" user "Board Geometry/Soldermask Top")
		(3 "B.Mask" user "Board Geometry/Soldermask Bottom")
		(17 "Dwgs.User" user "User.Drawings")
		(19 "Cmts.User" user "User.Comments")
		(21 "Eco1.User" user "User.Eco1")
		(23 "Eco2.User" user "User.Eco2")
		(25 "Edge.Cuts" user "Board Geometry/Outline")
		(27 "Margin" user)
		(31 "F.CrtYd" user "Package Geometry/Place Bound Top")
		(29 "B.CrtYd" user "Package Geometry/Place Bound Bottom")
		(35 "F.Fab" user "Ref Des/Assembly Top")
		(33 "B.Fab" user "Ref Des/Assembly Bottom")
	)
	(footprint ""
		(layer "F.Cu")
		(at 431.434748 -258.091686)
		(property "Reference" "J11"
			(at -3.683 -81.702148 0)
			(unlocked yes)
			(layer "F.SilkS")
			(effects
				(font
					(size 0.7874 0.5842)
					(thickness 0.1524)
				)
				(justify left)
			)
		)
		(property "Value" ""
			(at 0 0 0)
			(layer "F.Fab")
			(effects
				(font
					(size 1.27 1.27)
				)
			)
		)
		(duplicate_pad_numbers_are_jumpers no)
		(pad "229" smd rect
			(at 2.050034 13.17498 270)
			(size 0.519938 1.4986)
			(layers "F.Cu" "F.Mask" "F.Paste")
			(net "M_F_CPU0_SB_CS_N<1>")
		)
		(pad "230" smd rect
			(at 2.050034 14.025118 270)
			(size 0.519938 1.4986)
			(layers "F.Cu" "F.Mask" "F.Paste")
			(net "GND")
		)
		(pad "231" smd rect
			(at 2.050034 14.875002 270)
			(size 0.519938 1.4986)
			(layers "F.Cu" "F.Mask" "F.Paste")
			(net "TP_CHF_CPU0_DIMM1_FRU_5")
		)
		(pad "232" smd rect
			(at 2.050034 15.724886 270)
			(size 0.519938 1.4986)
			(layers "F.Cu" "F.Mask" "F.Paste")
			(net "TP_CHF_CPU0_DIMM1_FRU_6")
		)
		(pad "233" smd rect
			(at 2.050034 16.575024 270)
			(size 0.519938 1.4986)
			(layers "F.Cu" "F.Mask" "F.Paste")
			(net "GND")
		)
		(pad "234" smd rect
			(at 2.050034 17.424908 270)
			(size 0.519938 1.4986)
			(layers "F.Cu" "F.Mask" "F.Paste")
			(net "M_F_CPU0_SB_CB<6>")
		)
		(pad "235" smd rect
			(at 2.050034 18.275046 270)
			(size 0.519938 1.4986)
			(layers "F.Cu" "F.Mask" "F.Paste")
			(net "GND")
		)
		(pad "236" smd rect
			(at 2.050034 19.12493 270)
			(size 0.519938 1.4986)
			(layers "F.Cu" "F.Mask" "F.Paste")
			(net "M_F_CPU0_SB_CB<7>")
		)
		(pad "237" smd rect
			(at 2.050034 19.975068 270)
			(size 0.519938 1.4986)
			(layers "F.Cu" "F.Mask" "F.Paste")
			(net "GND")
		)
		(pad "238" smd rect
			(at 2.050034 20.824952 270)
			(size 0.519938 1.4986)
			(layers "F.Cu" "F.Mask" "F.Paste")
			(net "M_F_CPU0_SB_DQS_DN<4>")
		)
		(pad "239" smd rect
			(at 2.050034 21.67509 270)
			(size 0.519938 1.4986)
			(layers "F.Cu" "F.Mask" "F.Paste")
			(net "M_F_CPU0_SB_DQS_DP<4>")
		)
		(pad "240" smd rect
			(at 2.050034 22.524974 270)
			(size 0.519938 1.4986)
			(layers "F.Cu" "F.Mask" "F.Paste")
			(net "GND")
		)
		(pad "241" smd rect
			(at 2.050034 23.375112 270)
			(size 0.519938 1.4986)
			(layers "F.Cu" "F.Mask" "F.Paste")
			(net "M_F_CPU0_SB_CB<2>")
		)
		(pad "242" smd rect
			(at 2.050034 24.224996 270)
			(size 0.519938 1.4986)
			(layers "F.Cu" "F.Mask" "F.Paste")
			(net "GND")
		)
		(pad "243" smd rect
			(at 2.050034 25.07488 270)
			(size 0.519938 1.4986)
			(layers "F.Cu" "F.Mask" "F.Paste")
			(net "M_F_CPU0_SB_CB<3>")
		)
		(pad "244" smd rect
			(at 2.050034 25.925018 270)
			(size 0.519938 1.4986)
			(layers "F.Cu" "F.Mask" "F.Paste")
			(net "GND")
		)
		(pad "245" smd rect
			(at 2.050034 26.774902 270)
			(size 0.519938 1.4986)
			(layers "F.Cu" "F.Mask" "F.Paste")
			(net "M_F_CPU0_SB_DQ<2>")
		)
		(pad "246" smd rect
			(at 2.050034 27.62504 270)
			(size 0.519938 1.4986)
			(layers "F.Cu" "F.Mask" "F.Paste")
			(net "GND")
		)
		(pad "247" smd rect
			(at 2.050034 28.474924 270)
			(size 0.519938 1.4986)
			(layers "F.Cu" "F.Mask" "F.Paste")
			(net "M_F_CPU0_SB_DQ<3>")
		)
		(pad "248" smd rect
			(at 2.050034 29.325062 270)
			(size 0.519938 1.4986)
			(layers "F.Cu" "F.Mask" "F.Paste")
			(net "GND")
		)
		(pad "249" smd rect
			(at 2.050034 30.174946 270)
			(size 0.519938 1.4986)
			(layers "F.Cu" "F.Mask" "F.Paste")
			(net "M_F_CPU0_SB_DQS_DN<5>")
		)
		(pad "250" smd rect
			(at 2.050034 31.025084 270)
			(size 0.519938 1.4986)
			(layers "F.Cu" "F.Mask" "F.Paste")
			(net "M_F_CPU0_SB_DQS_DP<5>")
		)
		(pad "251" smd rect
			(at 2.050034 31.874968 270)
			(size 0.519938 1.4986)
			(layers "F.Cu" "F.Mask" "F.Paste")
			(net "GND")
		)
		(pad "252" smd rect
			(at 2.050034 32.725106 270)
			(size 0.519938 1.4986)
			(layers "F.Cu" "F.Mask" "F.Paste")
			(net "M_F_CPU0_SB_DQ<6>")
		)
		(pad "253" smd rect
			(at 2.050034 33.57499 270)
			(size 0.519938 1.4986)
			(layers "F.Cu" "F.Mask" "F.Paste")
			(net "GND")
		)
		(pad "254" smd rect
			(at 2.050034 34.425128 270)
			(size 0.519938 1.4986)
			(layers "F.Cu" "F.Mask" "F.Paste")
			(net "M_F_CPU0_SB_DQ<7>")
		)
		(pad "255" smd rect
			(at 2.050034 35.275012 270)
			(size 0.519938 1.4986)
			(layers "F.Cu" "F.Mask" "F.Paste")
			(net "GND")
		)
		(pad "256" smd rect
			(at 2.050034 36.124896 270)
			(size 0.519938 1.4986)
			(layers "F.Cu" "F.Mask" "F.Paste")
			(net "M_F_CPU0_SB_DQ<10>")
		)
		(pad "257" smd rect
			(at 2.050034 36.975034 270)
			(size 0.519938 1.4986)
			(layers "F.Cu" "F.Mask" "F.Paste")
			(net "GND")
		)
		(pad "258" smd rect
			(at 2.050034 37.824918 270)
			(size 0.519938 1.4986)
			(layers "F.Cu" "F.Mask" "F.Paste")
			(net "M_F_CPU0_SB_DQ<11>")
		)
		(pad "259" smd rect
			(at 2.050034 38.675056 270)
			(size 0.519938 1.4986)
			(layers "F.Cu" "F.Mask" "F.Paste")
			(net "GND")
		)
		(pad "260" smd rect
			(at 2.050034 39.52494 270)
			(size 0.519938 1.4986)
			(layers "F.Cu" "F.Mask" "F.Paste")
			(net "M_F_CPU0_SB_DQS_DN<6>")
		)
		(pad "261" smd rect
			(at 2.050034 40.375078 270)
			(size 0.519938 1.4986)
			(layers "F.Cu" "F.Mask" "F.Paste")
			(net "M_F_CPU0_SB_DQS_DP<6>")
		)
		(pad "262" smd rect
			(at 2.050034 41.224962 270)
			(size 0.519938 1.4986)
			(layers "F.Cu" "F.Mask" "F.Paste")
			(net "GND")
		)
		(pad "263" smd rect
			(at 2.050034 42.0751 270)
			(size 0.519938 1.4986)
			(layers "F.Cu" "F.Mask" "F.Paste")
			(net "M_F_CPU0_SB_DQ<14>")
		)
		(pad "264" smd rect
			(at 2.050034 42.924984 270)
			(size 0.519938 1.4986)
			(layers "F.Cu" "F.Mask" "F.Paste")
			(net "GND")
		)
		(pad "265" smd rect
			(at 2.050034 43.775122 270)
			(size 0.519938 1.4986)
			(layers "F.Cu" "F.Mask" "F.Paste")
			(net "M_F_CPU0_SB_DQ<15>")
		)
		(pad "266" smd rect
			(at 2.050034 44.625006 270)
			(size 0.519938 1.4986)
			(layers "F.Cu" "F.Mask" "F.Paste")
			(net "GND")
		)
		(pad "267" smd rect
			(at 2.050034 45.47489 270)
			(size 0.519938 1.4986)
			(layers "F.Cu" "F.Mask" "F.Paste")
			(net "M_F_CPU0_SB_DQ<18>")
		)
		(pad "268" smd rect
			(at 2.050034 46.325028 270)
			(size 0.519938 1.4986)
			(layers "F.Cu" "F.Mask" "F.Paste")
			(net "GND")
		)
		(pad "269" smd rect
			(at 2.050034 47.174912 270)
			(size 0.519938 1.4986)
			(layers "F.Cu" "F.Mask" "F.Paste")
			(net "M_F_CPU0_SB_DQ<19>")
		)
		(pad "270" smd rect
			(at 2.050034 48.02505 270)
			(size 0.519938 1.4986)
			(layers "F.Cu" "F.Mask" "F.Paste")
			(net "GND")
		)
		(pad "271" smd rect
			(at 2.050034 48.874934 270)
			(size 0.519938 1.4986)
			(layers "F.Cu" "F.Mask" "F.Paste")
			(net "M_F_CPU0_SB_DQS_DN<7>")
		)
		(pad "272" smd rect
			(at 2.050034 49.725072 270)
			(size 0.519938 1.4986)
			(layers "F.Cu" "F.Mask" "F.Paste")
			(net "M_F_CPU0_SB_DQS_DP<7>")
		)
		(pad "273" smd rect
			(at 2.050034 50.574956 270)
			(size 0.519938 1.4986)
			(layers "F.Cu" "F.Mask" "F.Paste")
			(net "GND")
		)
		(pad "274" smd rect
			(at 2.050034 51.425094 270)
			(size 0.519938 1.4986)
			(layers "F.Cu" "F.Mask" "F.Paste")
			(net "M_F_CPU0_SB_DQ<22>")
		)
	)
)
